(kicad_pcb
	(version 20260206)
	(generator "pcbnew")
	(generator_version "10.0")
	(general
		(thickness 1.6)
		(legacy_teardrops no)
	)
	(paper "A4")
	(title_block
		(title "Bryce Canyon_IOM_M2_16342-2_OCP.brd")
		(comment 1 "Bryce Canyon / footprints 356-363 of 1146")
	)
	(layers
		(0 "F.Cu" signal "TOP")
		(4 "In1.Cu" signal "L2GND")
		(6 "In2.Cu" signal "L3")
		(8 "In3.Cu" signal "L4VCC")
		(10 "In4.Cu" signal "L5VCC")
		(12 "In5.Cu" signal "L6")
		(14 "In6.Cu" signal "L7GND")
		(2 "B.Cu" signal "BOTTOM")
		(9 "F.Adhes" user "F.Adhesive")
		(11 "B.Adhes" user "B.Adhesive")
		(13 "F.Paste" user "Package Geometry/Pastemask Top")
		(15 "B.Paste" user "Package Geometry/Pastemask Bottom")
		(5 "F.SilkS" user "Ref Des/Silkscreen Top")
		(7 "B.SilkS" user "Ref Des/Silkscreen Bottom")
		(1 "F.Mask" user "Board Geometry/Soldermask Top")
		(3 "B.Mask" user "Board Geometry/Soldermask Bottom")
		(17 "Dwgs.User" user "User.Drawings")
		(19 "Cmts.User" user "User.Comments")
		(21 "Eco1.User" user "User.Eco1")
		(23 "Eco2.User" user "User.Eco2")
		(25 "Edge.Cuts" user "Board Geometry/Outline")
		(27 "Margin" user)
		(31 "F.CrtYd" user "Package Geometry/Place Bound Top")
		(29 "B.CrtYd" user "Package Geometry/Place Bound Bottom")
		(35 "F.Fab" user "Ref Des/Assembly Top")
		(33 "B.Fab" user "Ref Des/Assembly Bottom")
	)
	(footprint ""
		(layer "F.Cu")
		(at 68.6054 -118.2116 90)
		(property "Reference" "C74"
			(at 0 0 90)
			(layer "F.SilkS")
			(hide yes)
			(effects
				(font
					(size 1.27 1.27)
				)
			)
		)
		(property "Value" "SCD1U16V2KX-3GP"
			(at 1.1811 -2.7051 90)
			(unlocked yes)
			(layer "F.Fab")
			(hide yes)
			(effects
				(font
					(size 1.016 1.016)
					(thickness 0.1524)
				)
			)
		)
		(property "Device Type" "C402H22"
			(at 1.1811 -4.2291 90)
			(unlocked yes)
			(layer "F.Fab")
			(hide yes)
			(effects
				(font
					(size 1.016 1.016)
					(thickness 0.1524)
				)
			)
		)
		(duplicate_pad_numbers_are_jumpers no)
		(fp_rect
			(start -0.4318 0.9525)
			(end 0.4318 -0.9525)
			(stroke
				(width 0)
				(type default)
			)
			(fill no)
			(layer "F.CrtYd")
		)
		(fp_rect
			(start -0.4318 0.9525)
			(end 0.4318 -0.9525)
			(stroke
				(width 0)
				(type default)
			)
			(fill no)
			(layer "F.Fab")
		)
		(pad "1" smd custom
			(at 0 -0.4445 90)
			(size 0.1524 0.1524)
			(layers "F.Cu" "F.Mask" "F.Paste")
			(net "P3V3_STBY")
			(options
				(clearance outline)
				(anchor circle)
			)
			(primitives
				(gr_poly
					(pts
						(arc
							(start 0.3048 -0.2032)
							(mid 0.275042 -0.275042)
							(end 0.2032 -0.3048)
						)
						(arc
							(start -0.2032 -0.3048)
							(mid -0.275042 -0.275042)
							(end -0.3048 -0.2032)
						)
						(arc
							(start -0.3048 0.2032)
							(mid -0.275042 0.275042)
							(end -0.2032 0.3048)
						)
						(arc
							(start 0.2032 0.3048)
							(mid 0.275042 0.275042)
							(end 0.3048 0.2032)
						)
					)
					(width 0)
					(fill yes)
				)
			)
		)
		(pad "2" smd custom
			(at 0 0.4445 90)
			(size 0.1524 0.1524)
			(layers "F.Cu" "F.Mask" "F.Paste")
			(net "GND")
			(options
				(clearance outline)
				(anchor circle)
			)
			(primitives
				(gr_poly
					(pts
						(arc
							(start 0.3048 -0.2032)
							(mid 0.275042 -0.275042)
							(end 0.2032 -0.3048)
						)
						(arc
							(start -0.2032 -0.3048)
							(mid -0.275042 -0.275042)
							(end -0.3048 -0.2032)
						)
						(arc
							(start -0.3048 0.2032)
							(mid -0.275042 0.275042)
							(end -0.2032 0.3048)
						)
						(arc
							(start 0.2032 0.3048)
							(mid 0.275042 0.275042)
							(end 0.3048 0.2032)
						)
					)
					(width 0)
					(fill yes)
				)
			)
		)
	)
	(footprint ""
		(layer "F.Cu")
		(at 205.0034 -100.93452)
		(property "Reference" "TP216"
			(at 0 0 0)
			(layer "F.SilkS")
			(hide yes)
			(effects
				(font
					(size 1.27 1.27)
				)
			)
		)
		(property "Value" "TPAD32-GP"
			(at -0.0508 -1.6764 0)
			(unlocked yes)
			(layer "F.Fab")
			(hide yes)
			(effects
				(font
					(size 1.016 1.016)
					(thickness 0.1524)
				)
			)
		)
		(property "Device Type" "TPAD32"
			(at -0.0508 -3.2004 0)
			(unlocked yes)
			(layer "F.Fab")
			(hide yes)
			(effects
				(font
					(size 1.016 1.016)
					(thickness 0.1524)
				)
			)
		)
		(duplicate_pad_numbers_are_jumpers no)
		(fp_poly
			(pts
				(arc
					(start 0.4064 0)
					(mid -0.4064 0)
					(end 0.4064 0)
				)
			)
			(stroke
				(width 0)
				(type default)
			)
			(fill no)
			(layer "F.CrtYd")
		)
		(fp_poly
			(pts
				(arc
					(start 0.7112 0)
					(mid -0.7112 0)
					(end 0.7112 0)
				)
			)
			(stroke
				(width 0)
				(type default)
			)
			(fill no)
			(layer "F.Fab")
		)
		(pad "1" smd circle
			(at 0 0)
			(size 0.8128 0.8128)
			(layers "F.Cu" "F.Mask" "F.Paste")
			(net "TEMP_2_ALERT")
		)
	)
	(footprint ""
		(layer "F.Cu")
		(at 215.470994 -41.955212 90)
		(property "Reference" "R463"
			(at 0 0 90)
			(layer "F.SilkS")
			(hide yes)
			(effects
				(font
					(size 1.27 1.27)
				)
			)
		)
		(property "Value" "10KR2F-2-GP"
			(at 0.064008 -3.993896 90)
			(unlocked yes)
			(layer "F.Fab")
			(hide yes)
			(effects
				(font
					(size 1.016 1.016)
					(thickness 0.1524)
				)
			)
		)
		(property "Device Type" "R402H16"
			(at 0.064008 -5.517896 90)
			(unlocked yes)
			(layer "F.Fab")
			(hide yes)
			(effects
				(font
					(size 1.016 1.016)
					(thickness 0.1524)
				)
			)
		)
		(duplicate_pad_numbers_are_jumpers no)
		(fp_line
			(start 0.508 -0.9398)
			(end -0.508 -0.9398)
			(stroke
				(width 0.1524)
				(type default)
			)
			(layer "F.SilkS")
		)
		(fp_line
			(start -0.508 -0.9398)
			(end -0.508 0.9398)
			(stroke
				(width 0.1524)
				(type default)
			)
			(layer "F.SilkS")
		)
		(fp_rect
			(start -0.508 0.9398)
			(end 0.508 -0.9398)
			(stroke
				(width 0)
				(type default)
			)
			(fill no)
			(layer "F.CrtYd")
		)
		(fp_rect
			(start -0.508 0.9398)
			(end 0.508 -0.9398)
			(stroke
				(width 0)
				(type default)
			)
			(fill no)
			(layer "F.Fab")
		)
		(pad "1" smd custom
			(at 0 -0.4445 90)
			(size 0.1397 0.1397)
			(layers "F.Cu" "F.Mask" "F.Paste")
			(net "P12V_STBY")
			(options
				(clearance outline)
				(anchor circle)
			)
			(primitives
				(gr_poly
					(pts
						(arc
							(start -0.1778 -0.2794)
							(mid -0.249642 -0.249642)
							(end -0.2794 -0.1778)
						)
						(arc
							(start -0.2794 0.1778)
							(mid -0.249642 0.249642)
							(end -0.1778 0.2794)
						)
						(arc
							(start 0.1778 0.2794)
							(mid 0.249642 0.249642)
							(end 0.2794 0.1778)
						)
						(arc
							(start 0.2794 -0.1778)
							(mid 0.249642 -0.249642)
							(end 0.1778 -0.2794)
						)
					)
					(width 0)
					(fill yes)
				)
			)
		)
		(pad "2" smd custom
			(at 0 0.4445 90)
			(size 0.1397 0.1397)
			(layers "F.Cu" "F.Mask" "F.Paste")
			(net "P5V_EN_R")
			(options
				(clearance outline)
				(anchor circle)
			)
			(primitives
				(gr_poly
					(pts
						(arc
							(start -0.1778 -0.2794)
							(mid -0.249642 -0.249642)
							(end -0.2794 -0.1778)
						)
						(arc
							(start -0.2794 0.1778)
							(mid -0.249642 0.249642)
							(end -0.1778 0.2794)
						)
						(arc
							(start 0.1778 0.2794)
							(mid 0.249642 0.249642)
							(end 0.2794 0.1778)
						)
						(arc
							(start 0.2794 -0.1778)
							(mid 0.249642 -0.249642)
							(end 0.1778 -0.2794)
						)
					)
					(width 0)
					(fill yes)
				)
			)
		)
	)
	(footprint ""
		(layer "F.Cu")
		(at 74.680572 -168.346628 180)
		(property "Reference" "C241"
			(at 0 0 180)
			(layer "F.SilkS")
			(hide yes)
			(effects
				(font
					(size 1.27 1.27)
				)
			)
		)
		(property "Value" "SC1U16V3KX-5GP"
			(at 0 -2.8194 180)
			(unlocked yes)
			(layer "F.Fab")
			(hide yes)
			(effects
				(font
					(size 1.016 1.016)
					(thickness 0.1524)
				)
			)
		)
		(property "Device Type" "C603H36"
			(at 0 -4.3434 180)
			(unlocked yes)
			(layer "F.Fab")
			(hide yes)
			(effects
				(font
					(size 1.016 1.016)
					(thickness 0.1524)
				)
			)
		)
		(duplicate_pad_numbers_are_jumpers no)
		(fp_line
			(start 0.508 0)
			(end -0.508 0)
			(stroke
				(width 0.2032)
				(type default)
			)
			(layer "F.SilkS")
		)
		(fp_rect
			(start -0.5842 1.3335)
			(end 0.5842 -1.3335)
			(stroke
				(width 0)
				(type default)
			)
			(fill no)
			(layer "F.CrtYd")
		)
		(fp_rect
			(start -0.5842 1.3335)
			(end 0.5842 -1.3335)
			(stroke
				(width 0)
				(type default)
			)
			(fill no)
			(layer "F.Fab")
		)
		(pad "1" smd custom
			(at 0 -0.762 180)
			(size 0.2159 0.2159)
			(layers "F.Cu" "F.Mask" "F.Paste")
			(net "TPS74801_P1V15_STBY_BIAS")
			(options
				(clearance outline)
				(anchor circle)
			)
			(primitives
				(gr_poly
					(pts
						(arc
							(start -0.3302 -0.4318)
							(mid -0.402042 -0.402042)
							(end -0.4318 -0.3302)
						)
						(arc
							(start -0.4318 0.3302)
							(mid -0.402042 0.402042)
							(end -0.3302 0.4318)
						)
						(arc
							(start 0.3302 0.4318)
							(mid 0.402042 0.402042)
							(end 0.4318 0.3302)
						)
						(arc
							(start 0.4318 -0.3302)
							(mid 0.402042 -0.402042)
							(end 0.3302 -0.4318)
						)
					)
					(width 0)
					(fill yes)
				)
			)
		)
		(pad "2" smd custom
			(at 0 0.762 180)
			(size 0.2159 0.2159)
			(layers "F.Cu" "F.Mask" "F.Paste")
			(net "GND")
			(options
				(clearance outline)
				(anchor circle)
			)
			(primitives
				(gr_poly
					(pts
						(arc
							(start -0.3302 -0.4318)
							(mid -0.402042 -0.402042)
							(end -0.4318 -0.3302)
						)
						(arc
							(start -0.4318 0.3302)
							(mid -0.402042 0.402042)
							(end -0.3302 0.4318)
						)
						(arc
							(start 0.3302 0.4318)
							(mid 0.402042 0.402042)
							(end 0.4318 0.3302)
						)
						(arc
							(start 0.4318 -0.3302)
							(mid 0.402042 -0.402042)
							(end 0.3302 -0.4318)
						)
					)
					(width 0)
					(fill yes)
				)
			)
		)
	)
	(footprint ""
		(layer "F.Cu")
		(at 65.216532 -149.753066 90)
		(property "Reference" "C82"
			(at 0 0 90)
			(layer "F.SilkS")
			(hide yes)
			(effects
				(font
					(size 1.27 1.27)
				)
			)
		)
		(property "Value" "SC33P50V2JN-3GP"
			(at 1.1811 -2.7051 90)
			(unlocked yes)
			(layer "F.Fab")
			(hide yes)
			(effects
				(font
					(size 1.016 1.016)
					(thickness 0.1524)
				)
			)
		)
		(property "Device Type" "C402H22"
			(at 1.1811 -4.2291 90)
			(unlocked yes)
			(layer "F.Fab")
			(hide yes)
			(effects
				(font
					(size 1.016 1.016)
					(thickness 0.1524)
				)
			)
		)
		(duplicate_pad_numbers_are_jumpers no)
		(fp_rect
			(start -0.4318 0.9525)
			(end 0.4318 -0.9525)
			(stroke
				(width 0)
				(type default)
			)
			(fill no)
			(layer "F.CrtYd")
		)
		(fp_rect
			(start -0.4318 0.9525)
			(end 0.4318 -0.9525)
			(stroke
				(width 0)
				(type default)
			)
			(fill no)
			(layer "F.Fab")
		)
		(pad "1" smd custom
			(at 0 -0.4445 90)
			(size 0.1524 0.1524)
			(layers "F.Cu" "F.Mask" "F.Paste")
			(net "PD_USB2AVRES")
			(options
				(clearance outline)
				(anchor circle)
			)
			(primitives
				(gr_poly
					(pts
						(arc
							(start 0.3048 -0.2032)
							(mid 0.275042 -0.275042)
							(end 0.2032 -0.3048)
						)
						(arc
							(start -0.2032 -0.3048)
							(mid -0.275042 -0.275042)
							(end -0.3048 -0.2032)
						)
						(arc
							(start -0.3048 0.2032)
							(mid -0.275042 0.275042)
							(end -0.2032 0.3048)
						)
						(arc
							(start 0.2032 0.3048)
							(mid 0.275042 0.275042)
							(end 0.3048 0.2032)
						)
					)
					(width 0)
					(fill yes)
				)
			)
		)
		(pad "2" smd custom
			(at 0 0.4445 90)
			(size 0.1524 0.1524)
			(layers "F.Cu" "F.Mask" "F.Paste")
			(net "GND")
			(options
				(clearance outline)
				(anchor circle)
			)
			(primitives
				(gr_poly
					(pts
						(arc
							(start 0.3048 -0.2032)
							(mid 0.275042 -0.275042)
							(end 0.2032 -0.3048)
						)
						(arc
							(start -0.2032 -0.3048)
							(mid -0.275042 -0.275042)
							(end -0.3048 -0.2032)
						)
						(arc
							(start -0.3048 0.2032)
							(mid -0.275042 0.275042)
							(end -0.2032 0.3048)
						)
						(arc
							(start 0.2032 0.3048)
							(mid 0.275042 0.275042)
							(end 0.3048 0.2032)
						)
					)
					(width 0)
					(fill yes)
				)
			)
		)
	)
	(footprint ""
		(layer "F.Cu")
		(at 123.828556 -13.167614 90)
		(property "Reference" "R434"
			(at 0 0 90)
			(layer "F.SilkS")
			(hide yes)
			(effects
				(font
					(size 1.27 1.27)
				)
			)
		)
		(property "Value" "100R2D-GP"
			(at 0.064008 -3.993896 90)
			(unlocked yes)
			(layer "F.Fab")
			(hide yes)
			(effects
				(font
					(size 1.016 1.016)
					(thickness 0.1524)
				)
			)
		)
		(property "Device Type" "R402H14"
			(at 0.064008 -5.517896 90)
			(unlocked yes)
			(layer "F.Fab")
			(hide yes)
			(effects
				(font
					(size 1.016 1.016)
					(thickness 0.1524)
				)
			)
		)
		(duplicate_pad_numbers_are_jumpers no)
		(fp_line
			(start 0.508 -0.9398)
			(end -0.508 -0.9398)
			(stroke
				(width 0.1524)
				(type default)
			)
			(layer "F.SilkS")
		)
		(fp_line
			(start -0.508 -0.9398)
			(end -0.508 0.9398)
			(stroke
				(width 0.1524)
				(type default)
			)
			(layer "F.SilkS")
		)
		(fp_rect
			(start -0.508 0.9398)
			(end 0.508 -0.9398)
			(stroke
				(width 0)
				(type default)
			)
			(fill no)
			(layer "F.CrtYd")
		)
		(fp_rect
			(start -0.508 0.9398)
			(end 0.508 -0.9398)
			(stroke
				(width 0)
				(type default)
			)
			(fill no)
			(layer "F.Fab")
		)
		(pad "1" smd custom
			(at 0 -0.4445 90)
			(size 0.1397 0.1397)
			(layers "F.Cu" "F.Mask" "F.Paste")
			(net "GND")
			(options
				(clearance outline)
				(anchor circle)
			)
			(primitives
				(gr_poly
					(pts
						(arc
							(start -0.1778 -0.2794)
							(mid -0.249642 -0.249642)
							(end -0.2794 -0.1778)
						)
						(arc
							(start -0.2794 0.1778)
							(mid -0.249642 0.249642)
							(end -0.1778 0.2794)
						)
						(arc
							(start 0.1778 0.2794)
							(mid 0.249642 0.249642)
							(end 0.2794 0.1778)
						)
						(arc
							(start 0.2794 -0.1778)
							(mid 0.249642 -0.249642)
							(end 0.1778 -0.2794)
						)
					)
					(width 0)
					(fill yes)
				)
			)
		)
		(pad "2" smd custom
			(at 0 0.4445 90)
			(size 0.1397 0.1397)
			(layers "F.Cu" "F.Mask" "F.Paste")
			(net "MB0_TEMP_E")
			(options
				(clearance outline)
				(anchor circle)
			)
			(primitives
				(gr_poly
					(pts
						(arc
							(start -0.1778 -0.2794)
							(mid -0.249642 -0.249642)
							(end -0.2794 -0.1778)
						)
						(arc
							(start -0.2794 0.1778)
							(mid -0.249642 0.249642)
							(end -0.1778 0.2794)
						)
						(arc
							(start 0.1778 0.2794)
							(mid 0.249642 0.249642)
							(end 0.2794 0.1778)
						)
						(arc
							(start 0.2794 -0.1778)
							(mid 0.249642 -0.249642)
							(end 0.1778 -0.2794)
						)
					)
					(width 0)
					(fill yes)
				)
			)
		)
	)
	(footprint ""
		(layer "F.Cu")
		(at 20.591272 -129.074164 180)
		(property "Reference" "R225"
			(at 0 0 180)
			(layer "F.SilkS")
			(hide yes)
			(effects
				(font
					(size 1.27 1.27)
				)
			)
		)
		(property "Value" "120R2F-GP"
			(at 0.064008 -3.993896 180)
			(unlocked yes)
			(layer "F.Fab")
			(hide yes)
			(effects
				(font
					(size 1.016 1.016)
					(thickness 0.1524)
				)
			)
		)
		(property "Device Type" "R402H16"
			(at 0.064008 -5.517896 180)
			(unlocked yes)
			(layer "F.Fab")
			(hide yes)
			(effects
				(font
					(size 1.016 1.016)
					(thickness 0.1524)
				)
			)
		)
		(duplicate_pad_numbers_are_jumpers no)
		(fp_line
			(start 0.508 -0.9398)
			(end -0.508 -0.9398)
			(stroke
				(width 0.1524)
				(type default)
			)
			(layer "F.SilkS")
		)
		(fp_line
			(start -0.508 -0.9398)
			(end -0.508 0.9398)
			(stroke
				(width 0.1524)
				(type default)
			)
			(layer "F.SilkS")
		)
		(fp_rect
			(start -0.508 0.9398)
			(end 0.508 -0.9398)
			(stroke
				(width 0)
				(type default)
			)
			(fill no)
			(layer "F.CrtYd")
		)
		(fp_rect
			(start -0.508 0.9398)
			(end 0.508 -0.9398)
			(stroke
				(width 0)
				(type default)
			)
			(fill no)
			(layer "F.Fab")
		)
		(pad "1" smd custom
			(at 0 -0.4445 180)
			(size 0.1397 0.1397)
			(layers "F.Cu" "F.Mask" "F.Paste")
			(net "GND")
			(options
				(clearance outline)
				(anchor circle)
			)
			(primitives
				(gr_poly
					(pts
						(arc
							(start -0.1778 -0.2794)
							(mid -0.249642 -0.249642)
							(end -0.2794 -0.1778)
						)
						(arc
							(start -0.2794 0.1778)
							(mid -0.249642 0.249642)
							(end -0.1778 0.2794)
						)
						(arc
							(start 0.1778 0.2794)
							(mid 0.249642 0.249642)
							(end 0.2794 0.1778)
						)
						(arc
							(start 0.2794 -0.1778)
							(mid 0.249642 -0.249642)
							(end 0.1778 -0.2794)
						)
					)
					(width 0)
					(fill yes)
				)
			)
		)
		(pad "2" smd custom
			(at 0 0.4445 180)
			(size 0.1397 0.1397)
			(layers "F.Cu" "F.Mask" "F.Paste")
			(net "MEMCASN")
			(options
				(clearance outline)
				(anchor circle)
			)
			(primitives
				(gr_poly
					(pts
						(arc
							(start -0.1778 -0.2794)
							(mid -0.249642 -0.249642)
							(end -0.2794 -0.1778)
						)
						(arc
							(start -0.2794 0.1778)
							(mid -0.249642 0.249642)
							(end -0.1778 0.2794)
						)
						(arc
							(start 0.1778 0.2794)
							(mid 0.249642 0.249642)
							(end 0.2794 0.1778)
						)
						(arc
							(start 0.2794 -0.1778)
							(mid 0.249642 -0.249642)
							(end 0.1778 -0.2794)
						)
					)
					(width 0)
					(fill yes)
				)
			)
		)
	)
	(footprint ""
		(layer "F.Cu")
		(at 99.045776 -145.541746 -90)
		(property "Reference" "R426"
			(at 0 0 270)
			(layer "F.SilkS")
			(hide yes)
			(effects
				(font
					(size 1.27 1.27)
				)
			)
		)
		(property "Value" "0R2J-2-GP"
			(at 0.064008 -3.993896 270)
			(unlocked yes)
			(layer "F.Fab")
			(hide yes)
			(effects
				(font
					(size 1.016 1.016)
					(thickness 0.1524)
				)
			)
		)
		(property "Device Type" "R402H16"
			(at 0.064008 -5.517896 270)
			(unlocked yes)
			(layer "F.Fab")
			(hide yes)
			(effects
				(font
					(size 1.016 1.016)
					(thickness 0.1524)
				)
			)
		)
		(duplicate_pad_numbers_are_jumpers no)
		(fp_line
			(start -0.508 -0.9398)
			(end -0.508 0.9398)
			(stroke
				(width 0.1524)
				(type default)
			)
			(layer "F.SilkS")
		)
		(fp_line
			(start 0.508 -0.9398)
			(end -0.508 -0.9398)
			(stroke
				(width 0.1524)
				(type default)
			)
			(layer "F.SilkS")
		)
		(fp_rect
			(start -0.508 0.9398)
			(end 0.508 -0.9398)
			(stroke
				(width 0)
				(type default)
			)
			(fill no)
			(layer "F.CrtYd")
		)
		(fp_rect
			(start -0.508 0.9398)
			(end 0.508 -0.9398)
			(stroke
				(width 0)
				(type default)
			)
			(fill no)
			(layer "F.Fab")
		)
		(pad "1" smd custom
			(at 0 -0.4445 270)
			(size 0.1397 0.1397)
			(layers "F.Cu" "F.Mask" "F.Paste")
			(net "I2C_DEBUG_SDA_L")
			(options
				(clearance outline)
				(anchor circle)
			)
			(primitives
				(gr_poly
					(pts
						(arc
							(start -0.1778 -0.2794)
							(mid -0.249642 -0.249642)
							(end -0.2794 -0.1778)
						)
						(arc
							(start -0.2794 0.1778)
							(mid -0.249642 0.249642)
							(end -0.1778 0.2794)
						)
						(arc
							(start 0.1778 0.2794)
							(mid 0.249642 0.249642)
							(end 0.2794 0.1778)
						)
						(arc
							(start 0.2794 -0.1778)
							(mid 0.249642 -0.249642)
							(end 0.1778 -0.2794)
						)
					)
					(width 0)
					(fill yes)
				)
			)
		)
		(pad "2" smd custom
			(at 0 0.4445 270)
			(size 0.1397 0.1397)
			(layers "F.Cu" "F.Mask" "F.Paste")
			(net "I2C_DEBUG_SDA_R")
			(options
				(clearance outline)
				(anchor circle)
			)
			(primitives
				(gr_poly
					(pts
						(arc
							(start -0.1778 -0.2794)
							(mid -0.249642 -0.249642)
							(end -0.2794 -0.1778)
						)
						(arc
							(start -0.2794 0.1778)
							(mid -0.249642 0.249642)
							(end -0.1778 0.2794)
						)
						(arc
							(start 0.1778 0.2794)
							(mid 0.249642 0.249642)
							(end 0.2794 0.1778)
						)
						(arc
							(start 0.2794 -0.1778)
							(mid 0.249642 -0.249642)
							(end 0.1778 -0.2794)
						)
					)
					(width 0)
					(fill yes)
				)
			)
		)
	)
)
